# S9S_MB_2U (Grand Teton) — schematic netlist excerpt (pin names and nets, part order shuffled) for the footprints in the layout excerpt that follows; sources: Cadence DE-HDL packaged netlist, KiCad conversion of 03242023_DA0F0TMBIJ0_F0T_Motherboard_J_brd_V01_OCP.brd

PC1856  Q_CAP  22UF 10V 20% X6S  pkg C0805  page 258 : A = P5V_AUX ; B = GND
R3030  Q_RES  4.7K 5% CHIP  pkg 0402LF  page 148 : A = P3V3_AUX ; B = FM_SMB_1_ALERT_GPU_ISO_N
PC1224  Q_CAP  0.1UF 25V 10% X7R  pkg 0402  page 262 : A = P1V05_PCH_AUX ; B = GND

(kicad_pcb
	(version 20260206)
	(generator "pcbnew")
	(generator_version "10.0")
	(general
		(thickness 1.6)
		(legacy_teardrops no)
	)
	(paper "A4")
	(title_block
		(title "03242023_DA0F0TMBIJ0_F0T_Motherboard_J_brd_V01_OCP.brd")
		(comment 1 "Grand Teton / footprints 508-510 of 6105")
	)
	(layers
		(0 "F.Cu" signal "TOP")
		(4 "In1.Cu" signal "GND")
		(6 "In2.Cu" signal "IN1")
		(8 "In3.Cu" signal "GND1")
		(10 "In4.Cu" signal "IN2")
		(12 "In5.Cu" signal "GND2")
		(14 "In6.Cu" signal "IN3")
		(16 "In7.Cu" signal "GND3")
		(18 "In8.Cu" signal "VCC")
		(20 "In9.Cu" signal "VCC1")
		(22 "In10.Cu" signal "GND4")
		(24 "In11.Cu" signal "IN4")
		(26 "In12.Cu" signal "GND5")
		(28 "In13.Cu" signal "IN5")
		(30 "In14.Cu" signal "GND6")
		(32 "In15.Cu" signal "IN6")
		(34 "In16.Cu" signal "GND7")
		(2 "B.Cu" signal "BOTTOM")
		(9 "F.Adhes" user "F.Adhesive")
		(11 "B.Adhes" user "B.Adhesive")
		(13 "F.Paste" user "Package Geometry/Pastemask Top")
		(15 "B.Paste" user "Package Geometry/Pastemask Bottom")
		(5 "F.SilkS" user "Ref Des/Silkscreen Top")
		(7 "B.SilkS" user "Ref Des/Silkscreen Bottom")
		(1 "F.Mask" user "Board Geometry/Soldermask Top")
		(3 "B.Mask" user "Board Geometry/Soldermask Bottom")
		(17 "Dwgs.User" user "User.Drawings")
		(19 "Cmts.User" user "User.Comments")
		(21 "Eco1.User" user "User.Eco1")
		(23 "Eco2.User" user "User.Eco2")
		(25 "Edge.Cuts" user "Board Geometry/Outline")
		(27 "Margin" user)
		(31 "F.CrtYd" user "Package Geometry/Place Bound Top")
		(29 "B.CrtYd" user "Package Geometry/Place Bound Bottom")
		(35 "F.Fab" user "Ref Des/Assembly Top")
		(33 "B.Fab" user "Ref Des/Assembly Bottom")
	)
	(footprint ""
		(layer "F.Cu")
		(at 114.81308 -400.414998 -90)
		(property "Reference" "R3030"
			(at 0 0 270)
			(layer "F.SilkS")
			(hide yes)
			(effects
				(font
					(size 1.27 1.27)
				)
			)
		)
		(property "Value" ""
			(at 0 0 270)
			(layer "F.Fab")
			(effects
				(font
					(size 1.27 1.27)
				)
			)
		)
		(duplicate_pad_numbers_are_jumpers no)
		(fp_line
			(start -0.7874 0.4064)
			(end -0.7874 -0.4064)
			(stroke
				(width 0.1524)
				(type default)
			)
			(layer "F.SilkS")
		)
		(fp_line
			(start 0.7874 0.4064)
			(end -0.7874 0.4064)
			(stroke
				(width 0.1524)
				(type default)
			)
			(layer "F.SilkS")
		)
		(fp_line
			(start -0.7874 -0.4064)
			(end 0.7874 -0.4064)
			(stroke
				(width 0.1524)
				(type default)
			)
			(layer "F.SilkS")
		)
		(fp_line
			(start 0.7874 -0.4064)
			(end 0.7874 0.4064)
			(stroke
				(width 0.1524)
				(type default)
			)
			(layer "F.SilkS")
		)
		(fp_line
			(start -0.67945 0.3048)
			(end -0.67945 -0.305054)
			(stroke
				(width 0.1)
				(type default)
			)
			(layer "F.Fab")
		)
		(fp_line
			(start -0.12065 0.3048)
			(end -0.67945 0.3048)
			(stroke
				(width 0.1)
				(type default)
			)
			(layer "F.Fab")
		)
		(fp_line
			(start 0.120396 0.3048)
			(end 0.120396 0.2794)
			(stroke
				(width 0.1)
				(type default)
			)
			(layer "F.Fab")
		)
		(fp_line
			(start 0.67945 0.3048)
			(end 0.120396 0.3048)
			(stroke
				(width 0.1)
				(type default)
			)
			(layer "F.Fab")
		)
		(fp_line
			(start -0.12065 0.2794)
			(end -0.12065 0.3048)
			(stroke
				(width 0.1)
				(type default)
			)
			(layer "F.Fab")
		)
		(fp_line
			(start 0.120396 0.2794)
			(end -0.12065 0.2794)
			(stroke
				(width 0.1)
				(type default)
			)
			(layer "F.Fab")
		)
		(fp_line
			(start -0.12065 -0.2794)
			(end 0.12065 -0.2794)
			(stroke
				(width 0.1)
				(type default)
			)
			(layer "F.Fab")
		)
		(fp_line
			(start 0.12065 -0.2794)
			(end 0.12065 -0.3048)
			(stroke
				(width 0.1)
				(type default)
			)
			(layer "F.Fab")
		)
		(fp_line
			(start 0.12065 -0.3048)
			(end 0.67945 -0.3048)
			(stroke
				(width 0.1)
				(type default)
			)
			(layer "F.Fab")
		)
		(fp_line
			(start 0.67945 -0.3048)
			(end 0.67945 0.3048)
			(stroke
				(width 0.1)
				(type default)
			)
			(layer "F.Fab")
		)
		(fp_line
			(start -0.67945 -0.305054)
			(end -0.12065 -0.305054)
			(stroke
				(width 0.1)
				(type default)
			)
			(layer "F.Fab")
		)
		(fp_line
			(start -0.12065 -0.305054)
			(end -0.12065 -0.2794)
			(stroke
				(width 0.1)
				(type default)
			)
			(layer "F.Fab")
		)
		(pad "1" smd circle
			(at -0.40005 0 270)
			(size 0 0)
			(layers "F.Cu" "F.Mask" "F.Paste")
			(net "P3V3_AUX")
		)
		(pad "2" smd circle
			(at 0.40005 0 270)
			(size 0 0)
			(layers "F.Cu" "F.Mask" "F.Paste")
			(net "FM_SMB_1_ALERT_GPU_ISO_N")
		)
	)
	(footprint ""
		(layer "F.Cu")
		(at 272.394934 -67.455796 180)
		(property "Reference" "PC1224"
			(at 0 0 180)
			(layer "F.SilkS")
			(hide yes)
			(effects
				(font
					(size 1.27 1.27)
				)
			)
		)
		(property "Value" ""
			(at 0 0 180)
			(layer "F.Fab")
			(effects
				(font
					(size 1.27 1.27)
				)
			)
		)
		(duplicate_pad_numbers_are_jumpers no)
		(fp_line
			(start 0.7874 0.4064)
			(end -0.7874 0.4064)
			(stroke
				(width 0.1524)
				(type default)
			)
			(layer "F.SilkS")
		)
		(fp_line
			(start 0.7874 -0.4064)
			(end 0.7874 0.4064)
			(stroke
				(width 0.1524)
				(type default)
			)
			(layer "F.SilkS")
		)
		(fp_line
			(start -0.7874 0.4064)
			(end -0.7874 -0.4064)
			(stroke
				(width 0.1524)
				(type default)
			)
			(layer "F.SilkS")
		)
		(fp_line
			(start -0.7874 -0.4064)
			(end 0.7874 -0.4064)
			(stroke
				(width 0.1524)
				(type default)
			)
			(layer "F.SilkS")
		)
		(fp_line
			(start 0.67945 0.3048)
			(end 0.120396 0.3048)
			(stroke
				(width 0.1)
				(type default)
			)
			(layer "F.Fab")
		)
		(fp_line
			(start 0.67945 -0.3048)
			(end 0.67945 0.3048)
			(stroke
				(width 0.1)
				(type default)
			)
			(layer "F.Fab")
		)
		(fp_line
			(start 0.12065 -0.2794)
			(end 0.12065 -0.3048)
			(stroke
				(width 0.1)
				(type default)
			)
			(layer "F.Fab")
		)
		(fp_line
			(start 0.12065 -0.3048)
			(end 0.67945 -0.3048)
			(stroke
				(width 0.1)
				(type default)
			)
			(layer "F.Fab")
		)
		(fp_line
			(start 0.120396 0.3048)
			(end 0.120396 0.2794)
			(stroke
				(width 0.1)
				(type default)
			)
			(layer "F.Fab")
		)
		(fp_line
			(start 0.120396 0.2794)
			(end -0.12065 0.2794)
			(stroke
				(width 0.1)
				(type default)
			)
			(layer "F.Fab")
		)
		(fp_line
			(start -0.12065 0.3048)
			(end -0.67945 0.3048)
			(stroke
				(width 0.1)
				(type default)
			)
			(layer "F.Fab")
		)
		(fp_line
			(start -0.12065 0.2794)
			(end -0.12065 0.3048)
			(stroke
				(width 0.1)
				(type default)
			)
			(layer "F.Fab")
		)
		(fp_line
			(start -0.12065 -0.2794)
			(end 0.12065 -0.2794)
			(stroke
				(width 0.1)
				(type default)
			)
			(layer "F.Fab")
		)
		(fp_line
			(start -0.12065 -0.305054)
			(end -0.12065 -0.2794)
			(stroke
				(width 0.1)
				(type default)
			)
			(layer "F.Fab")
		)
		(fp_line
			(start -0.67945 0.3048)
			(end -0.67945 -0.305054)
			(stroke
				(width 0.1)
				(type default)
			)
			(layer "F.Fab")
		)
		(fp_line
			(start -0.67945 -0.305054)
			(end -0.12065 -0.305054)
			(stroke
				(width 0.1)
				(type default)
			)
			(layer "F.Fab")
		)
		(pad "1" smd circle
			(at -0.40005 0 180)
			(size 0 0)
			(layers "F.Cu" "F.Mask" "F.Paste")
			(net "P1V05_PCH_AUX")
		)
		(pad "2" smd circle
			(at 0.40005 0 180)
			(size 0 0)
			(layers "F.Cu" "F.Mask" "F.Paste")
			(net "GND")
		)
	)
	(footprint ""
		(layer "F.Cu")
		(at 437.425846 -381.47498 180)
		(property "Reference" "PC1856"
			(at 0 0 180)
			(layer "F.SilkS")
			(hide yes)
			(effects
				(font
					(size 1.27 1.27)
				)
			)
		)
		(property "Value" ""
			(at 0 0 180)
			(layer "F.Fab")
			(effects
				(font
					(size 1.27 1.27)
				)
			)
		)
		(duplicate_pad_numbers_are_jumpers no)
		(fp_line
			(start 1.524 0.762)
			(end -1.524 0.762)
			(stroke
				(width 0.1524)
				(type default)
			)
			(layer "F.SilkS")
		)
		(fp_line
			(start 1.524 -0.762)
			(end 1.524 0.762)
			(stroke
				(width 0.1524)
				(type default)
			)
			(layer "F.SilkS")
		)
		(fp_line
			(start -1.524 0.762)
			(end -1.524 -0.762)
			(stroke
				(width 0.1524)
				(type default)
			)
			(layer "F.SilkS")
		)
		(fp_line
			(start -1.524 -0.762)
			(end 1.524 -0.762)
			(stroke
				(width 0.1524)
				(type default)
			)
			(layer "F.SilkS")
		)
		(fp_line
			(start 1.1049 0.724916)
			(end 1.1049 -0.724916)
			(stroke
				(width 0.1)
				(type default)
			)
			(layer "F.Fab")
		)
		(fp_line
			(start 1.1049 -0.724916)
			(end -1.1049 -0.724916)
			(stroke
				(width 0.1)
				(type default)
			)
			(layer "F.Fab")
		)
		(fp_line
			(start -1.1049 0.724916)
			(end 1.1049 0.724916)
			(stroke
				(width 0.1)
				(type default)
			)
			(layer "F.Fab")
		)
		(fp_line
			(start -1.1049 -0.724916)
			(end -1.1049 0.724916)
			(stroke
				(width 0.1)
				(type default)
			)
			(layer "F.Fab")
		)
		(pad "1" smd rect
			(at -0.889 0)
			(size 1.016 1.27)
			(layers "F.Cu" "F.Mask" "F.Paste")
			(net "P5V_AUX")
		)
		(pad "2" smd rect
			(at 0.889 0)
			(size 1.016 1.27)
			(layers "F.Cu" "F.Mask" "F.Paste")
			(net "GND")
		)
	)
)
